(kicad_pcb
	(version 20260206)
	(generator "pcbnew")
	(generator_version "10.0")
	(general
		(thickness 1.6)
		(legacy_teardrops no)
	)
	(paper "A4")
	(title_block
		(title "panther-plus-userver — 13130-1b_20150205.brd")
		(comment 1 "Honey Badger (Wiwynn) / footprints 888-893 of 1509")
	)
	(layers
		(0 "F.Cu" signal "TOP")
		(4 "In1.Cu" signal "L2")
		(6 "In2.Cu" signal "L3")
		(8 "In3.Cu" signal "L4")
		(10 "In4.Cu" signal "L5")
		(12 "In5.Cu" signal "L6")
		(14 "In6.Cu" signal "L7")
		(16 "In7.Cu" signal "L8")
		(18 "In8.Cu" signal "L9")
		(20 "In9.Cu" signal "L10")
		(22 "In10.Cu" signal "L11")
		(2 "B.Cu" signal "BOTTOM")
		(9 "F.Adhes" user "F.Adhesive")
		(11 "B.Adhes" user "B.Adhesive")
		(13 "F.Paste" user "Package Geometry/Pastemask Top")
		(15 "B.Paste" user "Package Geometry/Pastemask Bottom")
		(5 "F.SilkS" user "Ref Des/Silkscreen Top")
		(7 "B.SilkS" user "Ref Des/Silkscreen Bottom")
		(1 "F.Mask" user "Board Geometry/Soldermask Top")
		(3 "B.Mask" user "Board Geometry/Soldermask Bottom")
		(17 "Dwgs.User" user "User.Drawings")
		(19 "Cmts.User" user "User.Comments")
		(21 "Eco1.User" user "User.Eco1")
		(23 "Eco2.User" user "User.Eco2")
		(25 "Edge.Cuts" user "Board Geometry/Outline")
		(27 "Margin" user)
		(31 "F.CrtYd" user "Package Geometry/Place Bound Top")
		(29 "B.CrtYd" user "Package Geometry/Place Bound Bottom")
		(35 "F.Fab" user "Ref Des/Assembly Top")
		(33 "B.Fab" user "Ref Des/Assembly Bottom")
	)
	(footprint ""
		(layer "B.Cu")
		(at 203.4794 -62.5348 90)
		(property "Reference" "PC161"
			(at 0 0 90)
			(layer "B.SilkS")
			(hide yes)
			(effects
				(font
					(size 1.27 1.27)
				)
				(justify mirror)
			)
		)
		(property "Value" "SC22U6D3V5MX-2GP"
			(at 0 -4.9022 90)
			(unlocked yes)
			(layer "B.Fab")
			(hide yes)
			(effects
				(font
					(size 1.016 1.016)
					(thickness 0.1524)
				)
				(justify mirror)
			)
		)
		(property "Device Type" "C805H58"
			(at 0 -6.8072 90)
			(unlocked yes)
			(layer "B.Fab")
			(hide yes)
			(effects
				(font
					(size 1.016 1.016)
					(thickness 0.1524)
				)
				(justify mirror)
			)
		)
		(duplicate_pad_numbers_are_jumpers no)
		(fp_line
			(start -0.6096 0)
			(end 0.6096 0)
			(stroke
				(width 0.3048)
				(type default)
			)
			(layer "B.SilkS")
		)
		(fp_poly
			(pts
				(xy 0.9017 1.4351) (xy -0.9017 1.4351) (xy -0.9017 -1.4351) (xy 0.9017 -1.4351)
			)
			(stroke
				(width 0)
				(type default)
			)
			(fill no)
			(layer "B.CrtYd")
		)
		(fp_poly
			(pts
				(xy -0.9017 1.4351) (xy -0.9017 -1.4351) (xy 0.9017 -1.4351) (xy 0.9017 1.4351)
			)
			(stroke
				(width 0)
				(type default)
			)
			(fill no)
			(layer "B.Fab")
		)
		(pad "1" smd rect
			(at 0 -0.8382 270)
			(size 1.5494 0.9398)
			(layers "B.Cu" "B.Mask" "B.Paste")
			(net "PV_VDDR")
		)
		(pad "2" smd rect
			(at 0 0.8382 270)
			(size 1.5494 0.9398)
			(layers "B.Cu" "B.Mask" "B.Paste")
			(net "GND")
		)
	)
	(footprint ""
		(layer "B.Cu")
		(at 106.970068 -46.361096)
		(property "Reference" "C148"
			(at 0 0 0)
			(layer "B.SilkS")
			(hide yes)
			(effects
				(font
					(size 1.27 1.27)
				)
				(justify mirror)
			)
		)
		(property "Value" "SC1U10V2KX-1GP"
			(at -1.1811 -2.7051 0)
			(unlocked yes)
			(layer "B.Fab")
			(hide yes)
			(effects
				(font
					(size 1.016 1.016)
					(thickness 0.1524)
				)
				(justify mirror)
			)
		)
		(property "Device Type" "C402H22"
			(at -1.1811 -4.2291 0)
			(unlocked yes)
			(layer "B.Fab")
			(hide yes)
			(effects
				(font
					(size 1.016 1.016)
					(thickness 0.1524)
				)
				(justify mirror)
			)
		)
		(duplicate_pad_numbers_are_jumpers no)
		(fp_rect
			(start 0.381 0.7366)
			(end -0.381 -0.7366)
			(stroke
				(width 0)
				(type default)
			)
			(fill no)
			(layer "B.CrtYd")
		)
		(fp_rect
			(start 0.381 0.7366)
			(end -0.381 -0.7366)
			(stroke
				(width 0)
				(type default)
			)
			(fill no)
			(layer "B.Fab")
		)
		(pad "1" smd custom
			(at 0 -0.4572 180)
			(size 0.1143 0.1143)
			(layers "B.Cu" "B.Mask" "B.Paste")
			(net "PV_VDDR")
			(options
				(clearance outline)
				(anchor circle)
			)
			(primitives
				(gr_poly
					(pts
						(arc
							(start -0.254 0.1778)
							(mid -0.239121 0.213721)
							(end -0.2032 0.2286)
						)
						(arc
							(start 0.2032 0.2286)
							(mid 0.239121 0.213721)
							(end 0.254 0.1778)
						)
						(arc
							(start 0.254 -0.1778)
							(mid 0.239121 -0.213721)
							(end 0.2032 -0.2286)
						)
						(arc
							(start -0.2032 -0.2286)
							(mid -0.239121 -0.213721)
							(end -0.254 -0.1778)
						)
					)
					(width 0)
					(fill yes)
				)
			)
		)
		(pad "2" smd custom
			(at 0 0.4572 180)
			(size 0.1143 0.1143)
			(layers "B.Cu" "B.Mask" "B.Paste")
			(net "GND")
			(options
				(clearance outline)
				(anchor circle)
			)
			(primitives
				(gr_poly
					(pts
						(arc
							(start -0.254 0.1778)
							(mid -0.239121 0.213721)
							(end -0.2032 0.2286)
						)
						(arc
							(start 0.2032 0.2286)
							(mid 0.239121 0.213721)
							(end 0.254 0.1778)
						)
						(arc
							(start 0.254 -0.1778)
							(mid 0.239121 -0.213721)
							(end 0.2032 -0.2286)
						)
						(arc
							(start -0.2032 -0.2286)
							(mid -0.239121 -0.213721)
							(end -0.254 -0.1778)
						)
					)
					(width 0)
					(fill yes)
				)
			)
		)
	)
	(footprint ""
		(layer "B.Cu")
		(at 107.823 -41.021 180)
		(property "Reference" "C175"
			(at 0 0 0)
			(layer "B.SilkS")
			(hide yes)
			(effects
				(font
					(size 1.27 1.27)
				)
				(justify mirror)
			)
		)
		(property "Value" "SC1U10V2KX-1GP"
			(at -1.1811 -2.7051 180)
			(unlocked yes)
			(layer "B.Fab")
			(hide yes)
			(effects
				(font
					(size 1.016 1.016)
					(thickness 0.1524)
				)
				(justify mirror)
			)
		)
		(property "Device Type" "C402H22"
			(at -1.1811 -4.2291 180)
			(unlocked yes)
			(layer "B.Fab")
			(hide yes)
			(effects
				(font
					(size 1.016 1.016)
					(thickness 0.1524)
				)
				(justify mirror)
			)
		)
		(duplicate_pad_numbers_are_jumpers no)
		(fp_rect
			(start 0.381 0.7366)
			(end -0.381 -0.7366)
			(stroke
				(width 0)
				(type default)
			)
			(fill no)
			(layer "B.CrtYd")
		)
		(fp_rect
			(start 0.381 0.7366)
			(end -0.381 -0.7366)
			(stroke
				(width 0)
				(type default)
			)
			(fill no)
			(layer "B.Fab")
		)
		(pad "1" smd custom
			(at 0 -0.4572)
			(size 0.1143 0.1143)
			(layers "B.Cu" "B.Mask" "B.Paste")
			(net "PVCCP")
			(options
				(clearance outline)
				(anchor circle)
			)
			(primitives
				(gr_poly
					(pts
						(arc
							(start -0.254 0.1778)
							(mid -0.239121 0.213721)
							(end -0.2032 0.2286)
						)
						(arc
							(start 0.2032 0.2286)
							(mid 0.239121 0.213721)
							(end 0.254 0.1778)
						)
						(arc
							(start 0.254 -0.1778)
							(mid 0.239121 -0.213721)
							(end 0.2032 -0.2286)
						)
						(arc
							(start -0.2032 -0.2286)
							(mid -0.239121 -0.213721)
							(end -0.254 -0.1778)
						)
					)
					(width 0)
					(fill yes)
				)
			)
		)
		(pad "2" smd custom
			(at 0 0.4572)
			(size 0.1143 0.1143)
			(layers "B.Cu" "B.Mask" "B.Paste")
			(net "GND")
			(options
				(clearance outline)
				(anchor circle)
			)
			(primitives
				(gr_poly
					(pts
						(arc
							(start -0.254 0.1778)
							(mid -0.239121 0.213721)
							(end -0.2032 0.2286)
						)
						(arc
							(start 0.2032 0.2286)
							(mid 0.239121 0.213721)
							(end 0.254 0.1778)
						)
						(arc
							(start 0.254 -0.1778)
							(mid 0.239121 -0.213721)
							(end 0.2032 -0.2286)
						)
						(arc
							(start -0.2032 -0.2286)
							(mid -0.239121 -0.213721)
							(end -0.254 -0.1778)
						)
					)
					(width 0)
					(fill yes)
				)
			)
		)
	)
	(footprint ""
		(layer "B.Cu")
		(at 87.122 -45.974 90)
		(property "Reference" "R311"
			(at 0 0 90)
			(layer "B.SilkS")
			(hide yes)
			(effects
				(font
					(size 1.27 1.27)
				)
				(justify mirror)
			)
		)
		(property "Value" "3KR2F-GP"
			(at -0.064008 -3.993896 90)
			(unlocked yes)
			(layer "B.Fab")
			(hide yes)
			(effects
				(font
					(size 1.016 1.016)
					(thickness 0.1524)
				)
				(justify mirror)
			)
		)
		(property "Device Type" "R402H16"
			(at -0.064008 -5.517896 90)
			(unlocked yes)
			(layer "B.Fab")
			(hide yes)
			(effects
				(font
					(size 1.016 1.016)
					(thickness 0.1524)
				)
				(justify mirror)
			)
		)
		(duplicate_pad_numbers_are_jumpers no)
		(fp_rect
			(start 0.381 0.8382)
			(end -0.381 -0.8382)
			(stroke
				(width 0)
				(type default)
			)
			(fill no)
			(layer "B.CrtYd")
		)
		(fp_rect
			(start 0.381 0.8382)
			(end -0.381 -0.8382)
			(stroke
				(width 0)
				(type default)
			)
			(fill no)
			(layer "B.Fab")
		)
		(pad "1" smd custom
			(at 0 -0.4318 270)
			(size 0.127 0.127)
			(layers "B.Cu" "B.Mask" "B.Paste")
			(net "PD_USB_OBSP")
			(options
				(clearance outline)
				(anchor circle)
			)
			(primitives
				(gr_poly
					(pts
						(arc
							(start -0.2032 0.2794)
							(mid -0.239121 0.264521)
							(end -0.254 0.2286)
						)
						(arc
							(start -0.254 -0.2286)
							(mid -0.239121 -0.264521)
							(end -0.2032 -0.2794)
						)
						(arc
							(start 0.2032 -0.2794)
							(mid 0.239121 -0.264521)
							(end 0.254 -0.2286)
						)
						(arc
							(start 0.254 0.2286)
							(mid 0.239121 0.264521)
							(end 0.2032 0.2794)
						)
					)
					(width 0)
					(fill yes)
				)
			)
		)
		(pad "2" smd custom
			(at 0 0.4318 270)
			(size 0.127 0.127)
			(layers "B.Cu" "B.Mask" "B.Paste")
			(net "GND")
			(options
				(clearance outline)
				(anchor circle)
			)
			(primitives
				(gr_poly
					(pts
						(arc
							(start -0.2032 0.2794)
							(mid -0.239121 0.264521)
							(end -0.254 0.2286)
						)
						(arc
							(start -0.254 -0.2286)
							(mid -0.239121 -0.264521)
							(end -0.2032 -0.2794)
						)
						(arc
							(start 0.2032 -0.2794)
							(mid 0.239121 -0.264521)
							(end 0.254 -0.2286)
						)
						(arc
							(start 0.254 0.2286)
							(mid 0.239121 0.264521)
							(end 0.2032 0.2794)
						)
					)
					(width 0)
					(fill yes)
				)
			)
		)
	)
	(footprint ""
		(layer "B.Cu")
		(at 95.758 -14.097 180)
		(property "Reference" "C318"
			(at 0 0 0)
			(layer "B.SilkS")
			(hide yes)
			(effects
				(font
					(size 1.27 1.27)
				)
				(justify mirror)
			)
		)
		(property "Value" "SC22U25V5MX-GP"
			(at 0 -4.9022 180)
			(unlocked yes)
			(layer "B.Fab")
			(hide yes)
			(effects
				(font
					(size 1.016 1.016)
					(thickness 0.1524)
				)
				(justify mirror)
			)
		)
		(property "Device Type" "C805H58"
			(at 0 -6.8072 180)
			(unlocked yes)
			(layer "B.Fab")
			(hide yes)
			(effects
				(font
					(size 1.016 1.016)
					(thickness 0.1524)
				)
				(justify mirror)
			)
		)
		(duplicate_pad_numbers_are_jumpers no)
		(fp_line
			(start -0.6096 0)
			(end 0.6096 0)
			(stroke
				(width 0.3048)
				(type default)
			)
			(layer "B.SilkS")
		)
		(fp_poly
			(pts
				(xy 0.9017 1.4351) (xy -0.9017 1.4351) (xy -0.9017 -1.4351) (xy 0.9017 -1.4351)
			)
			(stroke
				(width 0)
				(type default)
			)
			(fill no)
			(layer "B.CrtYd")
		)
		(fp_poly
			(pts
				(xy -0.9017 1.4351) (xy -0.9017 -1.4351) (xy 0.9017 -1.4351) (xy 0.9017 1.4351)
			)
			(stroke
				(width 0)
				(type default)
			)
			(fill no)
			(layer "B.Fab")
		)
		(pad "1" smd rect
			(at 0 -0.8382)
			(size 1.5494 0.9398)
			(layers "B.Cu" "B.Mask" "B.Paste")
			(net "P12V")
		)
		(pad "2" smd rect
			(at 0 0.8382)
			(size 1.5494 0.9398)
			(layers "B.Cu" "B.Mask" "B.Paste")
			(net "GND")
		)
	)
	(footprint ""
		(layer "B.Cu")
		(at 86.233 -15.113)
		(property "Reference" "PC202"
			(at 0 0 0)
			(layer "B.SilkS")
			(hide yes)
			(effects
				(font
					(size 1.27 1.27)
				)
				(justify mirror)
			)
		)
		(property "Value" "SC10U6D3V5KX-4GP"
			(at 0.0762 -6.1214 0)
			(unlocked yes)
			(layer "B.Fab")
			(hide yes)
			(effects
				(font
					(size 1.016 1.016)
					(thickness 0.1524)
				)
				(justify mirror)
			)
		)
		(property "Device Type" "C805H58"
			(at 0.0762 -8.1534 0)
			(unlocked yes)
			(layer "B.Fab")
			(hide yes)
			(effects
				(font
					(size 1.016 1.016)
					(thickness 0.1524)
				)
				(justify mirror)
			)
		)
		(duplicate_pad_numbers_are_jumpers no)
		(fp_line
			(start -0.6096 0)
			(end 0.6096 0)
			(stroke
				(width 0.3048)
				(type default)
			)
			(layer "B.SilkS")
		)
		(fp_poly
			(pts
				(xy 0.9017 1.4351) (xy -0.9017 1.4351) (xy -0.9017 -1.4351) (xy 0.9017 -1.4351)
			)
			(stroke
				(width 0)
				(type default)
			)
			(fill no)
			(layer "B.CrtYd")
		)
		(fp_poly
			(pts
				(xy -0.9017 1.4351) (xy -0.9017 -1.4351) (xy 0.9017 -1.4351) (xy 0.9017 1.4351)
			)
			(stroke
				(width 0)
				(type default)
			)
			(fill no)
			(layer "B.Fab")
		)
		(pad "1" smd rect
			(at 0 -0.8382 180)
			(size 1.5494 0.9398)
			(layers "B.Cu" "B.Mask" "B.Paste")
			(net "TPS74801_1V35_OUT")
		)
		(pad "2" smd rect
			(at 0 0.8382 180)
			(size 1.5494 0.9398)
			(layers "B.Cu" "B.Mask" "B.Paste")
			(net "GND")
		)
	)
)
